# BASEBOARD_FAB2 (Tioga Pass) — schematic netlist excerpt (pin names and nets, part order shuffled) for the footprints in the layout excerpt that follows; sources: Cadence DE-HDL packaged netlist, KiCad conversion of Wiwynn_Tioga_Pass_MB.brd

C5U15  CAP  100UF 4V 20% X5R  pkg 0805  page 217 : A = PVDDQ_ABC ; B = GND
U1L4  TTL1G07_A  74LVC1G07 IC  pkg SOP  page 111 : A = XDP_RST_CO_N ; Y = FM_DEBUG_RST_BTN_R1_N
C4M7  CAPP  68UF 16V 20% TANT  pkg 3018  page 195 : A = P12V_STBY ; B = GND

(kicad_pcb
	(version 20260206)
	(generator "pcbnew")
	(generator_version "10.0")
	(general
		(thickness 1.6)
		(legacy_teardrops no)
	)
	(paper "A4")
	(title_block
		(title "Wiwynn_Tioga_Pass_MB.brd")
		(comment 1 "Tioga Pass / footprints 3420-3422 of 4770")
	)
	(layers
		(0 "F.Cu" signal "TOP")
		(4 "In1.Cu" signal "L2GND")
		(6 "In2.Cu" signal "L3")
		(8 "In3.Cu" signal "L4GND")
		(10 "In4.Cu" signal "L5")
		(12 "In5.Cu" signal "L6GND")
		(14 "In6.Cu" signal "L7VCC")
		(16 "In7.Cu" signal "L8VCC")
		(18 "In8.Cu" signal "L9GND")
		(20 "In9.Cu" signal "L10")
		(22 "In10.Cu" signal "L11GND")
		(24 "In11.Cu" signal "L12")
		(26 "In12.Cu" signal "L13GND")
		(2 "B.Cu" signal "BOTTOM")
		(9 "F.Adhes" user "F.Adhesive")
		(11 "B.Adhes" user "B.Adhesive")
		(13 "F.Paste" user "Package Geometry/Pastemask Top")
		(15 "B.Paste" user "Package Geometry/Pastemask Bottom")
		(5 "F.SilkS" user "Ref Des/Silkscreen Top")
		(7 "B.SilkS" user "Ref Des/Silkscreen Bottom")
		(1 "F.Mask" user "Board Geometry/Soldermask Top")
		(3 "B.Mask" user "Board Geometry/Soldermask Bottom")
		(17 "Dwgs.User" user "User.Drawings")
		(19 "Cmts.User" user "User.Comments")
		(21 "Eco1.User" user "User.Eco1")
		(23 "Eco2.User" user "User.Eco2")
		(25 "Edge.Cuts" user "Board Geometry/Outline")
		(27 "Margin" user)
		(31 "F.CrtYd" user "Package Geometry/Place Bound Top")
		(29 "B.CrtYd" user "Package Geometry/Place Bound Bottom")
		(35 "F.Fab" user "Ref Des/Assembly Top")
		(33 "B.Fab" user "Ref Des/Assembly Bottom")
	)
	(footprint ""
		(layer "B.Cu")
		(at 267.081 3.81 90)
		(property "Reference" "C5U15"
			(at 0 0 90)
			(layer "B.SilkS")
			(hide yes)
			(effects
				(font
					(size 1.27 1.27)
				)
				(justify mirror)
			)
		)
		(property "Value" ""
			(at 0 0 90)
			(layer "B.Fab")
			(effects
				(font
					(size 1.27 1.27)
				)
				(justify mirror)
			)
		)
		(duplicate_pad_numbers_are_jumpers no)
		(fp_rect
			(start -0.7239 -0.2159)
			(end 0.7239 1.9939)
			(stroke
				(width 0)
				(type default)
			)
			(fill no)
			(layer "B.CrtYd")
		)
		(fp_line
			(start 0.7239 -0.2159)
			(end 0.7239 1.9939)
			(stroke
				(width 0.1)
				(type default)
			)
			(layer "B.Fab")
		)
		(fp_line
			(start -0.7239 -0.2159)
			(end 0.7239 -0.2159)
			(stroke
				(width 0.1)
				(type default)
			)
			(layer "B.Fab")
		)
		(fp_line
			(start 0.7239 1.9939)
			(end -0.7239 1.9939)
			(stroke
				(width 0.1)
				(type default)
			)
			(layer "B.Fab")
		)
		(fp_line
			(start -0.7239 1.9939)
			(end -0.7239 -0.2159)
			(stroke
				(width 0.1)
				(type default)
			)
			(layer "B.Fab")
		)
		(pad "1" smd rect
			(at 0 0 270)
			(size 1.27 1.016)
			(layers "B.Cu" "B.Mask" "B.Paste")
			(net "PVDDQ_ABC")
		)
		(pad "2" smd rect
			(at 0 1.778 270)
			(size 1.27 1.016)
			(layers "B.Cu" "B.Mask" "B.Paste")
			(net "GND")
		)
		(zone
			(layer "B.Cu")
			(hatch none 0.5)
			(connect_pads
				(clearance 0)
			)
			(min_thickness 0.25)
			(keepout
				(tracks not_allowed)
				(vias allowed)
				(pads allowed)
				(copperpour not_allowed)
				(footprints allowed)
			)
			(placement
				(enabled no)
				(sheetname "")
			)
			(fill
				(thermal_gap 0.5)
				(thermal_bridge_width 0.5)
				(island_removal_mode 0)
			)
			(polygon
				(pts
					(xy 267.589 4.445) (xy 268.351 4.445) (xy 268.351 3.175) (xy 267.589 3.175)
				)
			)
		)
	)
	(footprint ""
		(layer "B.Cu")
		(at 461.1116 -143.0274)
		(property "Reference" "U1L4"
			(at 1.28143 2.50952 270)
			(unlocked yes)
			(layer "B.SilkS")
			(effects
				(font
					(size 0.7874 0.5842)
					(thickness 0.1524)
				)
				(justify left mirror)
			)
		)
		(property "Value" ""
			(at 0 0 0)
			(layer "B.Fab")
			(effects
				(font
					(size 1.27 1.27)
				)
				(justify mirror)
			)
		)
		(duplicate_pad_numbers_are_jumpers no)
		(fp_circle
			(center 0.4699 -0.8382)
			(end 0.5969 -0.8382)
			(stroke
				(width 0.254)
				(type default)
			)
			(fill no)
			(layer "B.SilkS")
		)
		(fp_poly
			(pts
				(xy -0.21463 -0.450088) (xy -1.56337 -0.450088) (xy -1.56337 1.75006) (xy -0.21463 1.75006)
			)
			(stroke
				(width 0)
				(type default)
			)
			(fill no)
			(layer "B.CrtYd")
		)
		(fp_line
			(start -1.56337 -0.450088)
			(end -1.56337 1.75006)
			(stroke
				(width 0.1)
				(type default)
			)
			(layer "B.Fab")
		)
		(fp_line
			(start -1.56337 1.75006)
			(end -0.21463 1.75006)
			(stroke
				(width 0.1)
				(type default)
			)
			(layer "B.Fab")
		)
		(fp_line
			(start -0.21463 -0.450088)
			(end -1.56337 -0.450088)
			(stroke
				(width 0.1)
				(type default)
			)
			(layer "B.Fab")
		)
		(fp_line
			(start -0.21463 1.75006)
			(end -0.21463 -0.450088)
			(stroke
				(width 0.1)
				(type default)
			)
			(layer "B.Fab")
		)
		(fp_circle
			(center 0.4699 -0.8382)
			(end 0.5969 -0.8382)
			(stroke
				(width 0.254)
				(type default)
			)
			(fill no)
			(layer "B.Fab")
		)
		(pad "1" smd rect
			(at 0 0 180)
			(size 1.016 0.381)
			(layers "B.Cu" "B.Mask" "B.Paste")
			(net "Net_6475")
		)
		(pad "2" smd rect
			(at 0 0.649986 180)
			(size 1.016 0.381)
			(layers "B.Cu" "B.Mask" "B.Paste")
			(net "XDP_RST_CO_N")
		)
		(pad "3" smd rect
			(at 0 1.299972 180)
			(size 1.016 0.381)
			(layers "B.Cu" "B.Mask" "B.Paste")
			(net "GND")
		)
		(pad "4" smd rect
			(at -1.778 1.299972 180)
			(size 1.016 0.381)
			(layers "B.Cu" "B.Mask" "B.Paste")
			(net "FM_DEBUG_RST_BTN_R1_N")
		)
		(pad "5" smd rect
			(at -1.778 0 180)
			(size 1.016 0.381)
			(layers "B.Cu" "B.Mask" "B.Paste")
			(net "P3V3_STBY")
		)
	)
	(footprint ""
		(layer "B.Cu")
		(at 333.014574 -120.260364 90)
		(property "Reference" "C4M7"
			(at -0.15367 10.5918 0)
			(unlocked yes)
			(layer "B.SilkS")
			(effects
				(font
					(size 0.7874 0.5842)
					(thickness 0.1524)
				)
				(justify mirror)
			)
		)
		(property "Value" ""
			(at 0 0 90)
			(layer "B.Fab")
			(effects
				(font
					(size 1.27 1.27)
				)
				(justify mirror)
			)
		)
		(duplicate_pad_numbers_are_jumpers no)
		(fp_line
			(start 2.563114 -1.616456)
			(end 2.563114 1.633728)
			(stroke
				(width 0.1524)
				(type default)
			)
			(layer "B.SilkS")
		)
		(fp_line
			(start 1.6002 -1.616456)
			(end 2.563114 -1.616456)
			(stroke
				(width 0.1524)
				(type default)
			)
			(layer "B.SilkS")
		)
		(fp_line
			(start -1.6002 -1.616456)
			(end -2.504948 -1.616456)
			(stroke
				(width 0.1524)
				(type default)
			)
			(layer "B.SilkS")
		)
		(fp_line
			(start -2.504948 -1.616456)
			(end -2.504948 1.633728)
			(stroke
				(width 0.1524)
				(type default)
			)
			(layer "B.SilkS")
		)
		(fp_line
			(start 2.563114 1.633728)
			(end 1.6002 1.633728)
			(stroke
				(width 0.1524)
				(type default)
			)
			(layer "B.SilkS")
		)
		(fp_line
			(start -2.504948 1.633728)
			(end -1.6002 1.633728)
			(stroke
				(width 0.1524)
				(type default)
			)
			(layer "B.SilkS")
		)
		(fp_line
			(start 2.286 7.366)
			(end 2.286 1.632712)
			(stroke
				(width 0.1524)
				(type default)
			)
			(layer "B.SilkS")
		)
		(fp_line
			(start 2.286 7.366)
			(end 1.60147 7.366)
			(stroke
				(width 0.1524)
				(type default)
			)
			(layer "B.SilkS")
		)
		(fp_line
			(start -2.286 7.366)
			(end -2.286 1.63195)
			(stroke
				(width 0.1524)
				(type default)
			)
			(layer "B.SilkS")
		)
		(fp_line
			(start -2.286 7.366)
			(end -1.600708 7.366)
			(stroke
				(width 0.1524)
				(type default)
			)
			(layer "B.SilkS")
		)
		(fp_rect
			(start 2.286 7.366)
			(end -2.286 -0.254)
			(stroke
				(width 0)
				(type default)
			)
			(fill no)
			(layer "B.CrtYd")
		)
		(fp_line
			(start 2.286 -0.254)
			(end -2.286 -0.254)
			(stroke
				(width 0.1)
				(type default)
			)
			(layer "B.Fab")
		)
		(fp_line
			(start -2.286 -0.254)
			(end -2.286 7.366)
			(stroke
				(width 0.1)
				(type default)
			)
			(layer "B.Fab")
		)
		(fp_line
			(start 2.286 7.366)
			(end 2.286 -0.254)
			(stroke
				(width 0.1)
				(type default)
			)
			(layer "B.Fab")
		)
		(fp_line
			(start -2.286 7.366)
			(end 2.286 7.366)
			(stroke
				(width 0.1)
				(type default)
			)
			(layer "B.Fab")
		)
		(pad "1" smd rect
			(at 0 0 270)
			(size 2.54 3.048)
			(layers "B.Cu" "B.Mask" "B.Paste")
			(net "P12V_STBY")
		)
		(pad "2" smd rect
			(at 0 7.112 270)
			(size 2.54 3.048)
			(layers "B.Cu" "B.Mask" "B.Paste")
			(net "GND")
		)
	)
)
